# SCM (Grand Teton) — schematic netlist excerpt (pin names and nets, part order shuffled) for the footprints in the layout excerpt that follows; sources: Cadence DE-HDL packaged netlist, KiCad conversion of 12092022_DA0F0TMDCD0_F0T_Management_Board_D_brd_V3_OCP.brd

R220  Q_RES  0 5% CHIP  pkg 0402LF  page 36 : A = FM_BMC_UARTSW_MSB_N ; B = FM_UARTSW_MSB_N
C58  Q_CAP  1UF 25V 10% X6S  pkg C0402  page 16 : A = P1V2_AUX ; B = GND

(kicad_pcb
	(version 20260206)
	(generator "pcbnew")
	(generator_version "10.0")
	(general
		(thickness 1.6)
		(legacy_teardrops no)
	)
	(paper "A4")
	(title_block
		(title "12092022_DA0F0TMDCD0_F0T_Management_Board_D_brd_V3_OCP.brd")
		(comment 1 "Grand Teton / footprints 919-920 of 1440")
	)
	(layers
		(0 "F.Cu" signal "TOP")
		(4 "In1.Cu" signal "GND")
		(6 "In2.Cu" signal "IN1")
		(8 "In3.Cu" signal "GND1")
		(10 "In4.Cu" signal "IN2")
		(12 "In5.Cu" signal "VCC")
		(14 "In6.Cu" signal "VCC1")
		(16 "In7.Cu" signal "IN3")
		(18 "In8.Cu" signal "GND2")
		(20 "In9.Cu" signal "IN4")
		(22 "In10.Cu" signal "GND3")
		(2 "B.Cu" signal "BOTTOM")
		(9 "F.Adhes" user "F.Adhesive")
		(11 "B.Adhes" user "B.Adhesive")
		(13 "F.Paste" user "Package Geometry/Pastemask Top")
		(15 "B.Paste" user "Package Geometry/Pastemask Bottom")
		(5 "F.SilkS" user "Ref Des/Silkscreen Top")
		(7 "B.SilkS" user "Ref Des/Silkscreen Bottom")
		(1 "F.Mask" user "Board Geometry/Soldermask Top")
		(3 "B.Mask" user "Board Geometry/Soldermask Bottom")
		(17 "Dwgs.User" user "User.Drawings")
		(19 "Cmts.User" user "User.Comments")
		(21 "Eco1.User" user "User.Eco1")
		(23 "Eco2.User" user "User.Eco2")
		(25 "Edge.Cuts" user "Board Geometry/Outline")
		(27 "Margin" user)
		(31 "F.CrtYd" user "Package Geometry/Place Bound Top")
		(29 "B.CrtYd" user "Package Geometry/Place Bound Bottom")
		(35 "F.Fab" user "Ref Des/Assembly Top")
		(33 "B.Fab" user "Ref Des/Assembly Bottom")
	)
	(footprint ""
		(layer "B.Cu")
		(at 14.351 -106.426 90)
		(property "Reference" "R220"
			(at 0 0 90)
			(layer "B.SilkS")
			(hide yes)
			(effects
				(font
					(size 1.27 1.27)
				)
				(justify mirror)
			)
		)
		(property "Value" ""
			(at 0 0 90)
			(layer "B.Fab")
			(effects
				(font
					(size 1.27 1.27)
				)
				(justify mirror)
			)
		)
		(duplicate_pad_numbers_are_jumpers no)
		(fp_line
			(start 0.7874 -0.4064)
			(end -0.7874 -0.4064)
			(stroke
				(width 0.1524)
				(type default)
			)
			(layer "B.SilkS")
		)
		(fp_line
			(start -0.7874 -0.4064)
			(end -0.7874 0.4064)
			(stroke
				(width 0.1524)
				(type default)
			)
			(layer "B.SilkS")
		)
		(fp_line
			(start 0.7874 0.4064)
			(end 0.7874 -0.4064)
			(stroke
				(width 0.1524)
				(type default)
			)
			(layer "B.SilkS")
		)
		(fp_line
			(start -0.7874 0.4064)
			(end 0.7874 0.4064)
			(stroke
				(width 0.1524)
				(type default)
			)
			(layer "B.SilkS")
		)
		(fp_line
			(start 0.67945 -0.305054)
			(end 0.12065 -0.305054)
			(stroke
				(width 0.1)
				(type default)
			)
			(layer "B.Fab")
		)
		(fp_line
			(start 0.12065 -0.305054)
			(end 0.12065 -0.2794)
			(stroke
				(width 0.1)
				(type default)
			)
			(layer "B.Fab")
		)
		(fp_line
			(start -0.12065 -0.3048)
			(end -0.67945 -0.3048)
			(stroke
				(width 0.1)
				(type default)
			)
			(layer "B.Fab")
		)
		(fp_line
			(start -0.67945 -0.3048)
			(end -0.67945 0.3048)
			(stroke
				(width 0.1)
				(type default)
			)
			(layer "B.Fab")
		)
		(fp_line
			(start 0.12065 -0.2794)
			(end -0.12065 -0.2794)
			(stroke
				(width 0.1)
				(type default)
			)
			(layer "B.Fab")
		)
		(fp_line
			(start -0.12065 -0.2794)
			(end -0.12065 -0.3048)
			(stroke
				(width 0.1)
				(type default)
			)
			(layer "B.Fab")
		)
		(fp_line
			(start 0.12065 0.2794)
			(end 0.12065 0.3048)
			(stroke
				(width 0.1)
				(type default)
			)
			(layer "B.Fab")
		)
		(fp_line
			(start -0.120396 0.2794)
			(end 0.12065 0.2794)
			(stroke
				(width 0.1)
				(type default)
			)
			(layer "B.Fab")
		)
		(fp_line
			(start 0.67945 0.3048)
			(end 0.67945 -0.305054)
			(stroke
				(width 0.1)
				(type default)
			)
			(layer "B.Fab")
		)
		(fp_line
			(start 0.12065 0.3048)
			(end 0.67945 0.3048)
			(stroke
				(width 0.1)
				(type default)
			)
			(layer "B.Fab")
		)
		(fp_line
			(start -0.120396 0.3048)
			(end -0.120396 0.2794)
			(stroke
				(width 0.1)
				(type default)
			)
			(layer "B.Fab")
		)
		(fp_line
			(start -0.67945 0.3048)
			(end -0.120396 0.3048)
			(stroke
				(width 0.1)
				(type default)
			)
			(layer "B.Fab")
		)
		(pad "1" smd circle
			(at 0.40005 0 270)
			(size 0 0)
			(layers "B.Cu" "B.Mask" "B.Paste")
			(net "FM_BMC_UARTSW_MSB_N")
		)
		(pad "2" smd circle
			(at -0.40005 0 270)
			(size 0 0)
			(layers "B.Cu" "B.Mask" "B.Paste")
			(net "FM_UARTSW_MSB_N")
		)
	)
	(footprint ""
		(layer "B.Cu")
		(at 73.783698 -37.271706 -90)
		(property "Reference" "C58"
			(at 0 0 90)
			(layer "B.SilkS")
			(hide yes)
			(effects
				(font
					(size 1.27 1.27)
				)
				(justify mirror)
			)
		)
		(property "Value" ""
			(at 0 0 90)
			(layer "B.Fab")
			(effects
				(font
					(size 1.27 1.27)
				)
				(justify mirror)
			)
		)
		(duplicate_pad_numbers_are_jumpers no)
		(fp_line
			(start -0.7874 0.4064)
			(end 0.7874 0.4064)
			(stroke
				(width 0.1524)
				(type default)
			)
			(layer "B.SilkS")
		)
		(fp_line
			(start 0.7874 0.4064)
			(end 0.7874 -0.4064)
			(stroke
				(width 0.1524)
				(type default)
			)
			(layer "B.SilkS")
		)
		(fp_line
			(start -0.7874 -0.4064)
			(end -0.7874 0.4064)
			(stroke
				(width 0.1524)
				(type default)
			)
			(layer "B.SilkS")
		)
		(fp_line
			(start 0.7874 -0.4064)
			(end -0.7874 -0.4064)
			(stroke
				(width 0.1524)
				(type default)
			)
			(layer "B.SilkS")
		)
		(fp_line
			(start -0.67945 0.3048)
			(end -0.120396 0.3048)
			(stroke
				(width 0.1)
				(type default)
			)
			(layer "B.Fab")
		)
		(fp_line
			(start -0.120396 0.3048)
			(end -0.120396 0.2794)
			(stroke
				(width 0.1)
				(type default)
			)
			(layer "B.Fab")
		)
		(fp_line
			(start 0.12065 0.3048)
			(end 0.67945 0.3048)
			(stroke
				(width 0.1)
				(type default)
			)
			(layer "B.Fab")
		)
		(fp_line
			(start 0.67945 0.3048)
			(end 0.67945 -0.305054)
			(stroke
				(width 0.1)
				(type default)
			)
			(layer "B.Fab")
		)
		(fp_line
			(start -0.120396 0.2794)
			(end 0.12065 0.2794)
			(stroke
				(width 0.1)
				(type default)
			)
			(layer "B.Fab")
		)
		(fp_line
			(start 0.12065 0.2794)
			(end 0.12065 0.3048)
			(stroke
				(width 0.1)
				(type default)
			)
			(layer "B.Fab")
		)
		(fp_line
			(start -0.12065 -0.2794)
			(end -0.12065 -0.3048)
			(stroke
				(width 0.1)
				(type default)
			)
			(layer "B.Fab")
		)
		(fp_line
			(start 0.12065 -0.2794)
			(end -0.12065 -0.2794)
			(stroke
				(width 0.1)
				(type default)
			)
			(layer "B.Fab")
		)
		(fp_line
			(start -0.67945 -0.3048)
			(end -0.67945 0.3048)
			(stroke
				(width 0.1)
				(type default)
			)
			(layer "B.Fab")
		)
		(fp_line
			(start -0.12065 -0.3048)
			(end -0.67945 -0.3048)
			(stroke
				(width 0.1)
				(type default)
			)
			(layer "B.Fab")
		)
		(fp_line
			(start 0.12065 -0.305054)
			(end 0.12065 -0.2794)
			(stroke
				(width 0.1)
				(type default)
			)
			(layer "B.Fab")
		)
		(fp_line
			(start 0.67945 -0.305054)
			(end 0.12065 -0.305054)
			(stroke
				(width 0.1)
				(type default)
			)
			(layer "B.Fab")
		)
		(pad "1" smd circle
			(at 0.40005 0 90)
			(size 0 0)
			(layers "B.Cu" "B.Mask" "B.Paste")
			(net "P1V2_AUX")
		)
		(pad "2" smd circle
			(at -0.40005 0 90)
			(size 0 0)
			(layers "B.Cu" "B.Mask" "B.Paste")
			(net "GND")
		)
	)
)
